(kicad_pcb
	(version 20260206)
	(generator "pcbnew")
	(generator_version "10.0")
	(general
		(thickness 1.6)
		(legacy_teardrops no)
	)
	(paper "A4")
	(title_block
		(title "Bryce Canyon_F.DPB_16315-1-OCP.brd")
		(comment 1 "Bryce Canyon / footprints 868-874 of 2223")
	)
	(layers
		(0 "F.Cu" signal "TOP")
		(4 "In1.Cu" signal "L2GND")
		(6 "In2.Cu" signal "L3")
		(8 "In3.Cu" signal "L4GND")
		(10 "In4.Cu" signal "L5")
		(12 "In5.Cu" signal "L6VCC")
		(14 "In6.Cu" signal "L7VCC")
		(16 "In7.Cu" signal "L8")
		(18 "In8.Cu" signal "L9GND")
		(20 "In9.Cu" signal "L10")
		(22 "In10.Cu" signal "L11GND")
		(2 "B.Cu" signal "BOTTOM")
		(9 "F.Adhes" user "F.Adhesive")
		(11 "B.Adhes" user "B.Adhesive")
		(13 "F.Paste" user "Package Geometry/Pastemask Top")
		(15 "B.Paste" user "Package Geometry/Pastemask Bottom")
		(5 "F.SilkS" user "Ref Des/Silkscreen Top")
		(7 "B.SilkS" user "Ref Des/Silkscreen Bottom")
		(1 "F.Mask" user "Board Geometry/Soldermask Top")
		(3 "B.Mask" user "Board Geometry/Soldermask Bottom")
		(17 "Dwgs.User" user "User.Drawings")
		(19 "Cmts.User" user "User.Comments")
		(21 "Eco1.User" user "User.Eco1")
		(23 "Eco2.User" user "User.Eco2")
		(25 "Edge.Cuts" user "Board Geometry/Outline")
		(27 "Margin" user)
		(31 "F.CrtYd" user "Package Geometry/Place Bound Top")
		(29 "B.CrtYd" user "Package Geometry/Place Bound Bottom")
		(35 "F.Fab" user "Ref Des/Assembly Top")
		(33 "B.Fab" user "Ref Des/Assembly Bottom")
	)
	(footprint ""
		(layer "F.Cu")
		(at 260.8326 -284.4292 180)
		(property "Reference" "R105"
			(at 0 0 180)
			(layer "F.SilkS")
			(hide yes)
			(effects
				(font
					(size 1.27 1.27)
				)
			)
		)
		(property "Value" "0R2J-2-GP"
			(at 0.064008 -3.993896 180)
			(unlocked yes)
			(layer "F.Fab")
			(hide yes)
			(effects
				(font
					(size 1.016 1.016)
					(thickness 0.1524)
				)
			)
		)
		(property "Device Type" "R402H16"
			(at 0.064008 -5.517896 180)
			(unlocked yes)
			(layer "F.Fab")
			(hide yes)
			(effects
				(font
					(size 1.016 1.016)
					(thickness 0.1524)
				)
			)
		)
		(duplicate_pad_numbers_are_jumpers no)
		(fp_line
			(start 0.508 -0.9398)
			(end -0.508 -0.9398)
			(stroke
				(width 0.1524)
				(type default)
			)
			(layer "F.SilkS")
		)
		(fp_line
			(start -0.508 -0.9398)
			(end -0.508 0.9398)
			(stroke
				(width 0.1524)
				(type default)
			)
			(layer "F.SilkS")
		)
		(fp_rect
			(start -0.508 0.9398)
			(end 0.508 -0.9398)
			(stroke
				(width 0)
				(type default)
			)
			(fill no)
			(layer "F.CrtYd")
		)
		(fp_rect
			(start -0.508 0.9398)
			(end 0.508 -0.9398)
			(stroke
				(width 0)
				(type default)
			)
			(fill no)
			(layer "F.Fab")
		)
		(pad "1" smd custom
			(at 0 -0.4445 180)
			(size 0.1397 0.1397)
			(layers "F.Cu" "F.Mask" "F.Paste")
			(net "IO_EXP0_LED_SCL")
			(options
				(clearance outline)
				(anchor circle)
			)
			(primitives
				(gr_poly
					(pts
						(arc
							(start -0.1778 -0.2794)
							(mid -0.249642 -0.249642)
							(end -0.2794 -0.1778)
						)
						(arc
							(start -0.2794 0.1778)
							(mid -0.249642 0.249642)
							(end -0.1778 0.2794)
						)
						(arc
							(start 0.1778 0.2794)
							(mid 0.249642 0.249642)
							(end 0.2794 0.1778)
						)
						(arc
							(start 0.2794 -0.1778)
							(mid 0.249642 -0.249642)
							(end 0.1778 -0.2794)
						)
					)
					(width 0)
					(fill yes)
				)
			)
		)
		(pad "2" smd custom
			(at 0 0.4445 180)
			(size 0.1397 0.1397)
			(layers "F.Cu" "F.Mask" "F.Paste")
			(net "I2C_DRIVE_A_FLT_LED_SCL")
			(options
				(clearance outline)
				(anchor circle)
			)
			(primitives
				(gr_poly
					(pts
						(arc
							(start -0.1778 -0.2794)
							(mid -0.249642 -0.249642)
							(end -0.2794 -0.1778)
						)
						(arc
							(start -0.2794 0.1778)
							(mid -0.249642 0.249642)
							(end -0.1778 0.2794)
						)
						(arc
							(start 0.1778 0.2794)
							(mid 0.249642 0.249642)
							(end 0.2794 0.1778)
						)
						(arc
							(start 0.2794 -0.1778)
							(mid 0.249642 -0.249642)
							(end 0.1778 -0.2794)
						)
					)
					(width 0)
					(fill yes)
				)
			)
		)
	)
	(footprint ""
		(layer "F.Cu")
		(at 101.708458 -181.362858 90)
		(property "Reference" "R462"
			(at 0 0 90)
			(layer "F.SilkS")
			(hide yes)
			(effects
				(font
					(size 1.27 1.27)
				)
			)
		)
		(property "Value" "4K7R2J-2-GP"
			(at 0.064008 -3.993896 90)
			(unlocked yes)
			(layer "F.Fab")
			(hide yes)
			(effects
				(font
					(size 1.016 1.016)
					(thickness 0.1524)
				)
			)
		)
		(property "Device Type" "R402H16"
			(at 0.064008 -5.517896 90)
			(unlocked yes)
			(layer "F.Fab")
			(hide yes)
			(effects
				(font
					(size 1.016 1.016)
					(thickness 0.1524)
				)
			)
		)
		(duplicate_pad_numbers_are_jumpers no)
		(fp_line
			(start 0.508 -0.9398)
			(end -0.508 -0.9398)
			(stroke
				(width 0.1524)
				(type default)
			)
			(layer "F.SilkS")
		)
		(fp_line
			(start -0.508 -0.9398)
			(end -0.508 0.9398)
			(stroke
				(width 0.1524)
				(type default)
			)
			(layer "F.SilkS")
		)
		(fp_rect
			(start -0.508 0.9398)
			(end 0.508 -0.9398)
			(stroke
				(width 0)
				(type default)
			)
			(fill no)
			(layer "F.CrtYd")
		)
		(fp_rect
			(start -0.508 0.9398)
			(end 0.508 -0.9398)
			(stroke
				(width 0)
				(type default)
			)
			(fill no)
			(layer "F.Fab")
		)
		(pad "1" smd custom
			(at 0 -0.4445 90)
			(size 0.1397 0.1397)
			(layers "F.Cu" "F.Mask" "F.Paste")
			(net "DRIVE_A_3_ACT")
			(options
				(clearance outline)
				(anchor circle)
			)
			(primitives
				(gr_poly
					(pts
						(arc
							(start -0.1778 -0.2794)
							(mid -0.249642 -0.249642)
							(end -0.2794 -0.1778)
						)
						(arc
							(start -0.2794 0.1778)
							(mid -0.249642 0.249642)
							(end -0.1778 0.2794)
						)
						(arc
							(start 0.1778 0.2794)
							(mid 0.249642 0.249642)
							(end 0.2794 0.1778)
						)
						(arc
							(start 0.2794 -0.1778)
							(mid 0.249642 -0.249642)
							(end 0.1778 -0.2794)
						)
					)
					(width 0)
					(fill yes)
				)
			)
		)
		(pad "2" smd custom
			(at 0 0.4445 90)
			(size 0.1397 0.1397)
			(layers "F.Cu" "F.Mask" "F.Paste")
			(net "GND")
			(options
				(clearance outline)
				(anchor circle)
			)
			(primitives
				(gr_poly
					(pts
						(arc
							(start -0.1778 -0.2794)
							(mid -0.249642 -0.249642)
							(end -0.2794 -0.1778)
						)
						(arc
							(start -0.2794 0.1778)
							(mid -0.249642 0.249642)
							(end -0.1778 0.2794)
						)
						(arc
							(start 0.1778 0.2794)
							(mid 0.249642 0.249642)
							(end 0.2794 0.1778)
						)
						(arc
							(start 0.2794 -0.1778)
							(mid 0.249642 -0.249642)
							(end 0.1778 -0.2794)
						)
					)
					(width 0)
					(fill yes)
				)
			)
		)
	)
	(footprint ""
		(layer "F.Cu")
		(at 241.3762 -382.1938 180)
		(property "Reference" "R1152"
			(at 0 0 180)
			(layer "F.SilkS")
			(hide yes)
			(effects
				(font
					(size 1.27 1.27)
				)
			)
		)
		(property "Value" "100KR2F-L1-GP"
			(at 0.064008 -3.993896 180)
			(unlocked yes)
			(layer "F.Fab")
			(hide yes)
			(effects
				(font
					(size 1.016 1.016)
					(thickness 0.1524)
				)
			)
		)
		(property "Device Type" "R402H16"
			(at 0.064008 -5.517896 180)
			(unlocked yes)
			(layer "F.Fab")
			(hide yes)
			(effects
				(font
					(size 1.016 1.016)
					(thickness 0.1524)
				)
			)
		)
		(duplicate_pad_numbers_are_jumpers no)
		(fp_line
			(start 0.508 -0.9398)
			(end -0.508 -0.9398)
			(stroke
				(width 0.1524)
				(type default)
			)
			(layer "F.SilkS")
		)
		(fp_line
			(start -0.508 -0.9398)
			(end -0.508 0.9398)
			(stroke
				(width 0.1524)
				(type default)
			)
			(layer "F.SilkS")
		)
		(fp_rect
			(start -0.508 0.9398)
			(end 0.508 -0.9398)
			(stroke
				(width 0)
				(type default)
			)
			(fill no)
			(layer "F.CrtYd")
		)
		(fp_rect
			(start -0.508 0.9398)
			(end 0.508 -0.9398)
			(stroke
				(width 0)
				(type default)
			)
			(fill no)
			(layer "F.Fab")
		)
		(pad "1" smd custom
			(at 0 -0.4445 180)
			(size 0.1397 0.1397)
			(layers "F.Cu" "F.Mask" "F.Paste")
			(net "P12V_A")
			(options
				(clearance outline)
				(anchor circle)
			)
			(primitives
				(gr_poly
					(pts
						(arc
							(start -0.1778 -0.2794)
							(mid -0.249642 -0.249642)
							(end -0.2794 -0.1778)
						)
						(arc
							(start -0.2794 0.1778)
							(mid -0.249642 0.249642)
							(end -0.1778 0.2794)
						)
						(arc
							(start 0.1778 0.2794)
							(mid 0.249642 0.249642)
							(end 0.2794 0.1778)
						)
						(arc
							(start 0.2794 -0.1778)
							(mid 0.249642 -0.249642)
							(end 0.1778 -0.2794)
						)
					)
					(width 0)
					(fill yes)
				)
			)
		)
		(pad "2" smd custom
			(at 0 0.4445 180)
			(size 0.1397 0.1397)
			(layers "F.Cu" "F.Mask" "F.Paste")
			(net "MB3_P12V_PWGIN_R")
			(options
				(clearance outline)
				(anchor circle)
			)
			(primitives
				(gr_poly
					(pts
						(arc
							(start -0.1778 -0.2794)
							(mid -0.249642 -0.249642)
							(end -0.2794 -0.1778)
						)
						(arc
							(start -0.2794 0.1778)
							(mid -0.249642 0.249642)
							(end -0.1778 0.2794)
						)
						(arc
							(start 0.1778 0.2794)
							(mid 0.249642 0.249642)
							(end 0.2794 0.1778)
						)
						(arc
							(start 0.2794 -0.1778)
							(mid 0.249642 -0.249642)
							(end 0.1778 -0.2794)
						)
					)
					(width 0)
					(fill yes)
				)
			)
		)
	)
	(footprint ""
		(layer "F.Cu")
		(at 428.221902 -184.420002 -90)
		(property "Reference" "R614"
			(at 0 0 270)
			(layer "F.SilkS")
			(hide yes)
			(effects
				(font
					(size 1.27 1.27)
				)
			)
		)
		(property "Value" "2R6F-GP"
			(at -0.0508 -4.8514 270)
			(unlocked yes)
			(layer "F.Fab")
			(hide yes)
			(effects
				(font
					(size 1.016 1.016)
					(thickness 0.1524)
				)
			)
		)
		(property "Device Type" "R1206H26"
			(at 0 -6.3754 270)
			(unlocked yes)
			(layer "F.Fab")
			(hide yes)
			(effects
				(font
					(size 1.016 1.016)
					(thickness 0.1524)
				)
			)
		)
		(duplicate_pad_numbers_are_jumpers no)
		(fp_line
			(start -1.016 2.2352)
			(end -1.016 -2.2352)
			(stroke
				(width 0.1524)
				(type default)
			)
			(layer "F.SilkS")
		)
		(fp_line
			(start 1.016 2.2352)
			(end -1.016 2.2352)
			(stroke
				(width 0.1524)
				(type default)
			)
			(layer "F.SilkS")
		)
		(fp_line
			(start -1.016 -2.2352)
			(end 1.016 -2.2352)
			(stroke
				(width 0.1524)
				(type default)
			)
			(layer "F.SilkS")
		)
		(fp_line
			(start 1.016 -2.2352)
			(end 1.016 2.2352)
			(stroke
				(width 0.1524)
				(type default)
			)
			(layer "F.SilkS")
		)
		(fp_rect
			(start -1.0922 2.3114)
			(end 1.0922 -2.3114)
			(stroke
				(width 0)
				(type default)
			)
			(fill no)
			(layer "F.CrtYd")
		)
		(fp_poly
			(pts
				(xy -1.0922 -2.3114) (xy 1.0922 -2.3114) (xy 1.0922 2.3114) (xy -1.0922 2.3114)
			)
			(stroke
				(width 0)
				(type default)
			)
			(fill no)
			(layer "F.Fab")
		)
		(pad "1" smd rect
			(at 0 -1.397 270)
			(size 1.651 1.27)
			(layers "F.Cu" "F.Mask" "F.Paste")
			(net "P12V_HDD21")
		)
		(pad "2" smd rect
			(at 0 1.397 270)
			(size 1.651 1.27)
			(layers "F.Cu" "F.Mask" "F.Paste")
			(net "12V_PRE_21")
		)
	)
	(footprint ""
		(layer "F.Cu")
		(at 464.9089 -56.809894 -90)
		(property "Reference" "R925"
			(at 0 0 270)
			(layer "F.SilkS")
			(hide yes)
			(effects
				(font
					(size 1.27 1.27)
				)
			)
		)
		(property "Value" "300KR2F-GP"
			(at 0.064008 -3.993896 270)
			(unlocked yes)
			(layer "F.Fab")
			(hide yes)
			(effects
				(font
					(size 1.016 1.016)
					(thickness 0.1524)
				)
			)
		)
		(property "Device Type" "R402H16"
			(at 0.064008 -5.517896 270)
			(unlocked yes)
			(layer "F.Fab")
			(hide yes)
			(effects
				(font
					(size 1.016 1.016)
					(thickness 0.1524)
				)
			)
		)
		(duplicate_pad_numbers_are_jumpers no)
		(fp_line
			(start -0.508 -0.9398)
			(end -0.508 0.9398)
			(stroke
				(width 0.1524)
				(type default)
			)
			(layer "F.SilkS")
		)
		(fp_line
			(start 0.508 -0.9398)
			(end -0.508 -0.9398)
			(stroke
				(width 0.1524)
				(type default)
			)
			(layer "F.SilkS")
		)
		(fp_rect
			(start -0.508 0.9398)
			(end 0.508 -0.9398)
			(stroke
				(width 0)
				(type default)
			)
			(fill no)
			(layer "F.CrtYd")
		)
		(fp_rect
			(start -0.508 0.9398)
			(end 0.508 -0.9398)
			(stroke
				(width 0)
				(type default)
			)
			(fill no)
			(layer "F.Fab")
		)
		(pad "1" smd custom
			(at 0 -0.4445 270)
			(size 0.1397 0.1397)
			(layers "F.Cu" "F.Mask" "F.Paste")
			(net "SW_HDD_N34")
			(options
				(clearance outline)
				(anchor circle)
			)
			(primitives
				(gr_poly
					(pts
						(arc
							(start -0.1778 -0.2794)
							(mid -0.249642 -0.249642)
							(end -0.2794 -0.1778)
						)
						(arc
							(start -0.2794 0.1778)
							(mid -0.249642 0.249642)
							(end -0.1778 0.2794)
						)
						(arc
							(start 0.1778 0.2794)
							(mid 0.249642 0.249642)
							(end 0.2794 0.1778)
						)
						(arc
							(start 0.2794 -0.1778)
							(mid 0.249642 -0.249642)
							(end 0.1778 -0.2794)
						)
					)
					(width 0)
					(fill yes)
				)
			)
		)
		(pad "2" smd custom
			(at 0 0.4445 270)
			(size 0.1397 0.1397)
			(layers "F.Cu" "F.Mask" "F.Paste")
			(net "P12V_A")
			(options
				(clearance outline)
				(anchor circle)
			)
			(primitives
				(gr_poly
					(pts
						(arc
							(start -0.1778 -0.2794)
							(mid -0.249642 -0.249642)
							(end -0.2794 -0.1778)
						)
						(arc
							(start -0.2794 0.1778)
							(mid -0.249642 0.249642)
							(end -0.1778 0.2794)
						)
						(arc
							(start 0.1778 0.2794)
							(mid 0.249642 0.249642)
							(end 0.2794 0.1778)
						)
						(arc
							(start 0.2794 -0.1778)
							(mid 0.249642 -0.249642)
							(end 0.1778 -0.2794)
						)
					)
					(width 0)
					(fill yes)
				)
			)
		)
	)
	(footprint ""
		(layer "F.Cu")
		(at 437.671718 -294.424862 180)
		(property "Reference" "R320"
			(at 0 0 180)
			(layer "F.SilkS")
			(hide yes)
			(effects
				(font
					(size 1.27 1.27)
				)
			)
		)
		(property "Value" "130R3F-GP"
			(at -0.0254 -2.5146 180)
			(unlocked yes)
			(layer "F.Fab")
			(hide yes)
			(effects
				(font
					(size 1.016 1.016)
					(thickness 0.1524)
				)
			)
		)
		(property "Device Type" "R603H22"
			(at -0.0254 -4.0386 180)
			(unlocked yes)
			(layer "F.Fab")
			(hide yes)
			(effects
				(font
					(size 1.016 1.016)
					(thickness 0.1524)
				)
			)
		)
		(duplicate_pad_numbers_are_jumpers no)
		(fp_line
			(start 0.2032 0)
			(end 0.4826 0)
			(stroke
				(width 0.2032)
				(type default)
			)
			(layer "F.SilkS")
		)
		(fp_line
			(start -0.4826 0)
			(end -0.2032 0)
			(stroke
				(width 0.2032)
				(type default)
			)
			(layer "F.SilkS")
		)
		(fp_rect
			(start -0.5842 1.3335)
			(end 0.5842 -1.3335)
			(stroke
				(width 0)
				(type default)
			)
			(fill no)
			(layer "F.CrtYd")
		)
		(fp_rect
			(start -0.5842 1.3335)
			(end 0.5842 -1.3335)
			(stroke
				(width 0)
				(type default)
			)
			(fill no)
			(layer "F.Fab")
		)
		(pad "1" smd custom
			(at 0 -0.762 180)
			(size 0.2159 0.2159)
			(layers "F.Cu" "F.Mask" "F.Paste")
			(net "P5V_B")
			(options
				(clearance outline)
				(anchor circle)
			)
			(primitives
				(gr_poly
					(pts
						(arc
							(start -0.3302 -0.4318)
							(mid -0.402042 -0.402042)
							(end -0.4318 -0.3302)
						)
						(arc
							(start -0.4318 0.3302)
							(mid -0.402042 0.402042)
							(end -0.3302 0.4318)
						)
						(arc
							(start 0.3302 0.4318)
							(mid 0.402042 0.402042)
							(end 0.4318 0.3302)
						)
						(arc
							(start 0.4318 -0.3302)
							(mid 0.402042 -0.402042)
							(end 0.3302 -0.4318)
						)
					)
					(width 0)
					(fill yes)
				)
			)
		)
		(pad "2" smd custom
			(at 0 0.762 180)
			(size 0.2159 0.2159)
			(layers "F.Cu" "F.Mask" "F.Paste")
			(net "FLT_HDD34")
			(options
				(clearance outline)
				(anchor circle)
			)
			(primitives
				(gr_poly
					(pts
						(arc
							(start -0.3302 -0.4318)
							(mid -0.402042 -0.402042)
							(end -0.4318 -0.3302)
						)
						(arc
							(start -0.4318 0.3302)
							(mid -0.402042 0.402042)
							(end -0.3302 0.4318)
						)
						(arc
							(start 0.3302 0.4318)
							(mid 0.402042 0.402042)
							(end 0.4318 0.3302)
						)
						(arc
							(start 0.4318 -0.3302)
							(mid 0.402042 -0.402042)
							(end 0.3302 -0.4318)
						)
					)
					(width 0)
					(fill yes)
				)
			)
		)
	)
	(footprint ""
		(layer "F.Cu")
		(at 241.4016 -242.6716 180)
		(property "Reference" "R83"
			(at 0 0 180)
			(layer "F.SilkS")
			(hide yes)
			(effects
				(font
					(size 1.27 1.27)
				)
			)
		)
		(property "Value" "0R2J-2-GP"
			(at 0.064008 -3.993896 180)
			(unlocked yes)
			(layer "F.Fab")
			(hide yes)
			(effects
				(font
					(size 1.016 1.016)
					(thickness 0.1524)
				)
			)
		)
		(property "Device Type" "R402H16"
			(at 0.064008 -5.517896 180)
			(unlocked yes)
			(layer "F.Fab")
			(hide yes)
			(effects
				(font
					(size 1.016 1.016)
					(thickness 0.1524)
				)
			)
		)
		(duplicate_pad_numbers_are_jumpers no)
		(fp_line
			(start 0.508 -0.9398)
			(end -0.508 -0.9398)
			(stroke
				(width 0.1524)
				(type default)
			)
			(layer "F.SilkS")
		)
		(fp_line
			(start -0.508 -0.9398)
			(end -0.508 0.9398)
			(stroke
				(width 0.1524)
				(type default)
			)
			(layer "F.SilkS")
		)
		(fp_rect
			(start -0.508 0.9398)
			(end 0.508 -0.9398)
			(stroke
				(width 0)
				(type default)
			)
			(fill no)
			(layer "F.CrtYd")
		)
		(fp_rect
			(start -0.508 0.9398)
			(end 0.508 -0.9398)
			(stroke
				(width 0)
				(type default)
			)
			(fill no)
			(layer "F.Fab")
		)
		(pad "1" smd custom
			(at 0 -0.4445 180)
			(size 0.1397 0.1397)
			(layers "F.Cu" "F.Mask" "F.Paste")
			(net "IO_EXP2_SDA")
			(options
				(clearance outline)
				(anchor circle)
			)
			(primitives
				(gr_poly
					(pts
						(arc
							(start -0.1778 -0.2794)
							(mid -0.249642 -0.249642)
							(end -0.2794 -0.1778)
						)
						(arc
							(start -0.2794 0.1778)
							(mid -0.249642 0.249642)
							(end -0.1778 0.2794)
						)
						(arc
							(start 0.1778 0.2794)
							(mid 0.249642 0.249642)
							(end 0.2794 0.1778)
						)
						(arc
							(start 0.2794 -0.1778)
							(mid 0.249642 -0.249642)
							(end 0.1778 -0.2794)
						)
					)
					(width 0)
					(fill yes)
				)
			)
		)
		(pad "2" smd custom
			(at 0 0.4445 180)
			(size 0.1397 0.1397)
			(layers "F.Cu" "F.Mask" "F.Paste")
			(net "I2C_DRIVE_A_PWR_SDA")
			(options
				(clearance outline)
				(anchor circle)
			)
			(primitives
				(gr_poly
					(pts
						(arc
							(start -0.1778 -0.2794)
							(mid -0.249642 -0.249642)
							(end -0.2794 -0.1778)
						)
						(arc
							(start -0.2794 0.1778)
							(mid -0.249642 0.249642)
							(end -0.1778 0.2794)
						)
						(arc
							(start 0.1778 0.2794)
							(mid 0.249642 0.249642)
							(end 0.2794 0.1778)
						)
						(arc
							(start 0.2794 -0.1778)
							(mid 0.249642 -0.249642)
							(end 0.1778 -0.2794)
						)
					)
					(width 0)
					(fill yes)
				)
			)
		)
	)
)
